FILE_TYPE = MULTI_PHYS_TABLE;

PART 'RS31312R'

{========================================================================================}
:VALUE      | PART_TYPE | MATERIAL | PART_NUMBER    = STANDARD | LIFECYCLE     | PART_NUMBER   | JEDEC_TYPE     | DESCRIPTION            | MANUFTR | MANUF_PN   | RD_CMPLS_LVL | CMPLS_LVL | FROM_PJ    | CLASS | DIP_SMD | DATA               | EE_CHECK_LIST | FP_ECN         | PSL | CREATOR | STATUS | MSD | ESD_CDM | ESD_HBM | ESD_MM | PIN_LENGTH_SHORT_PIN | PIN_LENGTH_LONG_PIN | CREATEDAY  ;
{========================================================================================}
 'RS31312R' | 'SMLF'    | 'IC'     | 'AL031312000'(!) = ''       | ''               | 'AL031312000' |'QFN22_TH_3X5'| 'IC(22P)RS31312R(QFN)' | 'RDS'   | 'RS31312R' | 'EP(V1)'     | ''        | 'F0T-GREG' | 'IC'  | ''      | 'RDS_RS31312R.pdf' | ''            | 'RS31312R.msg' | ''  | ''      | ''     | ''  | ''      | ''      | ''     | '0 MILS'             | '0 MILS'            | '20220608'
 'RS31312R' | 'SMLF'    | 'EMPTY'  | 'AL031312000'(!) = ''       | ''               | 'AL031312000' |'QFN22_TH_3X5'| 'IC(22P)RS31312R(QFN)' | 'RDS'   | 'RS31312R' | 'EP(V1)'     | ''        | 'F0T-GREG' | 'IC'  | ''      | 'RDS_RS31312R.pdf' | ''            | 'RS31312R.msg' | ''  | ''      | ''     | ''  | ''      | ''      | ''     | '0 MILS'             | '0 MILS'            | '20220608'

END_PART

END.

